(kicad_pcb
	(version 20260206)
	(generator "pcbnew")
	(generator_version "10.0")
	(general
		(thickness 1.6)
		(legacy_teardrops no)
	)
	(paper "A4")
	(title_block
		(title "12092022_DA0F0TMDCD0_F0T_Management_Board_D_brd_V3_OCP.brd")
		(comment 1 "Grand Teton / footprints 136-141 of 1440")
	)
	(layers
		(0 "F.Cu" signal "TOP")
		(4 "In1.Cu" signal "GND")
		(6 "In2.Cu" signal "IN1")
		(8 "In3.Cu" signal "GND1")
		(10 "In4.Cu" signal "IN2")
		(12 "In5.Cu" signal "VCC")
		(14 "In6.Cu" signal "VCC1")
		(16 "In7.Cu" signal "IN3")
		(18 "In8.Cu" signal "GND2")
		(20 "In9.Cu" signal "IN4")
		(22 "In10.Cu" signal "GND3")
		(2 "B.Cu" signal "BOTTOM")
		(9 "F.Adhes" user "F.Adhesive")
		(11 "B.Adhes" user "B.Adhesive")
		(13 "F.Paste" user "Package Geometry/Pastemask Top")
		(15 "B.Paste" user "Package Geometry/Pastemask Bottom")
		(5 "F.SilkS" user "Ref Des/Silkscreen Top")
		(7 "B.SilkS" user "Ref Des/Silkscreen Bottom")
		(1 "F.Mask" user "Board Geometry/Soldermask Top")
		(3 "B.Mask" user "Board Geometry/Soldermask Bottom")
		(17 "Dwgs.User" user "User.Drawings")
		(19 "Cmts.User" user "User.Comments")
		(21 "Eco1.User" user "User.Eco1")
		(23 "Eco2.User" user "User.Eco2")
		(25 "Edge.Cuts" user "Board Geometry/Outline")
		(27 "Margin" user)
		(31 "F.CrtYd" user "Package Geometry/Place Bound Top")
		(29 "B.CrtYd" user "Package Geometry/Place Bound Bottom")
		(35 "F.Fab" user "Ref Des/Assembly Top")
		(33 "B.Fab" user "Ref Des/Assembly Bottom")
	)
	(footprint ""
		(layer "F.Cu")
		(at 40.767 -51.8414 90)
		(property "Reference" "R853"
			(at 0 0 90)
			(layer "F.SilkS")
			(hide yes)
			(effects
				(font
					(size 1.27 1.27)
				)
			)
		)
		(property "Value" ""
			(at 0 0 90)
			(layer "F.Fab")
			(effects
				(font
					(size 1.27 1.27)
				)
			)
		)
		(duplicate_pad_numbers_are_jumpers no)
		(fp_line
			(start 0.7874 -0.4064)
			(end 0.7874 0.4064)
			(stroke
				(width 0.1524)
				(type default)
			)
			(layer "F.SilkS")
		)
		(fp_line
			(start -0.7874 -0.4064)
			(end 0.7874 -0.4064)
			(stroke
				(width 0.1524)
				(type default)
			)
			(layer "F.SilkS")
		)
		(fp_line
			(start 0.7874 0.4064)
			(end -0.7874 0.4064)
			(stroke
				(width 0.1524)
				(type default)
			)
			(layer "F.SilkS")
		)
		(fp_line
			(start -0.7874 0.4064)
			(end -0.7874 -0.4064)
			(stroke
				(width 0.1524)
				(type default)
			)
			(layer "F.SilkS")
		)
		(fp_line
			(start -0.12065 -0.305054)
			(end -0.12065 -0.2794)
			(stroke
				(width 0.1)
				(type default)
			)
			(layer "F.Fab")
		)
		(fp_line
			(start -0.67945 -0.305054)
			(end -0.12065 -0.305054)
			(stroke
				(width 0.1)
				(type default)
			)
			(layer "F.Fab")
		)
		(fp_line
			(start 0.67945 -0.3048)
			(end 0.67945 0.3048)
			(stroke
				(width 0.1)
				(type default)
			)
			(layer "F.Fab")
		)
		(fp_line
			(start 0.12065 -0.3048)
			(end 0.67945 -0.3048)
			(stroke
				(width 0.1)
				(type default)
			)
			(layer "F.Fab")
		)
		(fp_line
			(start 0.12065 -0.2794)
			(end 0.12065 -0.3048)
			(stroke
				(width 0.1)
				(type default)
			)
			(layer "F.Fab")
		)
		(fp_line
			(start -0.12065 -0.2794)
			(end 0.12065 -0.2794)
			(stroke
				(width 0.1)
				(type default)
			)
			(layer "F.Fab")
		)
		(fp_line
			(start 0.120396 0.2794)
			(end -0.12065 0.2794)
			(stroke
				(width 0.1)
				(type default)
			)
			(layer "F.Fab")
		)
		(fp_line
			(start -0.12065 0.2794)
			(end -0.12065 0.3048)
			(stroke
				(width 0.1)
				(type default)
			)
			(layer "F.Fab")
		)
		(fp_line
			(start 0.67945 0.3048)
			(end 0.120396 0.3048)
			(stroke
				(width 0.1)
				(type default)
			)
			(layer "F.Fab")
		)
		(fp_line
			(start 0.120396 0.3048)
			(end 0.120396 0.2794)
			(stroke
				(width 0.1)
				(type default)
			)
			(layer "F.Fab")
		)
		(fp_line
			(start -0.12065 0.3048)
			(end -0.67945 0.3048)
			(stroke
				(width 0.1)
				(type default)
			)
			(layer "F.Fab")
		)
		(fp_line
			(start -0.67945 0.3048)
			(end -0.67945 -0.305054)
			(stroke
				(width 0.1)
				(type default)
			)
			(layer "F.Fab")
		)
		(pad "1" smd circle
			(at -0.40005 0 90)
			(size 0 0)
			(layers "F.Cu" "F.Mask" "F.Paste")
			(net "FM_INTRUDER_R_N")
		)
		(pad "2" smd circle
			(at 0.40005 0 90)
			(size 0 0)
			(layers "F.Cu" "F.Mask" "F.Paste")
			(net "FM_INTRUDER_N")
		)
	)
	(footprint ""
		(layer "F.Cu")
		(at 83.217258 -37.703506)
		(property "Reference" "R830"
			(at 0 0 0)
			(layer "F.SilkS")
			(hide yes)
			(effects
				(font
					(size 1.27 1.27)
				)
			)
		)
		(property "Value" ""
			(at 0 0 0)
			(layer "F.Fab")
			(effects
				(font
					(size 1.27 1.27)
				)
			)
		)
		(duplicate_pad_numbers_are_jumpers no)
		(fp_line
			(start -0.7874 -0.4064)
			(end 0.7874 -0.4064)
			(stroke
				(width 0.1524)
				(type default)
			)
			(layer "F.SilkS")
		)
		(fp_line
			(start -0.7874 0.4064)
			(end -0.7874 -0.4064)
			(stroke
				(width 0.1524)
				(type default)
			)
			(layer "F.SilkS")
		)
		(fp_line
			(start 0.7874 -0.4064)
			(end 0.7874 0.4064)
			(stroke
				(width 0.1524)
				(type default)
			)
			(layer "F.SilkS")
		)
		(fp_line
			(start 0.7874 0.4064)
			(end -0.7874 0.4064)
			(stroke
				(width 0.1524)
				(type default)
			)
			(layer "F.SilkS")
		)
		(fp_line
			(start -0.67945 -0.305054)
			(end -0.12065 -0.305054)
			(stroke
				(width 0.1)
				(type default)
			)
			(layer "F.Fab")
		)
		(fp_line
			(start -0.67945 0.3048)
			(end -0.67945 -0.305054)
			(stroke
				(width 0.1)
				(type default)
			)
			(layer "F.Fab")
		)
		(fp_line
			(start -0.12065 -0.305054)
			(end -0.12065 -0.2794)
			(stroke
				(width 0.1)
				(type default)
			)
			(layer "F.Fab")
		)
		(fp_line
			(start -0.12065 -0.2794)
			(end 0.12065 -0.2794)
			(stroke
				(width 0.1)
				(type default)
			)
			(layer "F.Fab")
		)
		(fp_line
			(start -0.12065 0.2794)
			(end -0.12065 0.3048)
			(stroke
				(width 0.1)
				(type default)
			)
			(layer "F.Fab")
		)
		(fp_line
			(start -0.12065 0.3048)
			(end -0.67945 0.3048)
			(stroke
				(width 0.1)
				(type default)
			)
			(layer "F.Fab")
		)
		(fp_line
			(start 0.120396 0.2794)
			(end -0.12065 0.2794)
			(stroke
				(width 0.1)
				(type default)
			)
			(layer "F.Fab")
		)
		(fp_line
			(start 0.120396 0.3048)
			(end 0.120396 0.2794)
			(stroke
				(width 0.1)
				(type default)
			)
			(layer "F.Fab")
		)
		(fp_line
			(start 0.12065 -0.3048)
			(end 0.67945 -0.3048)
			(stroke
				(width 0.1)
				(type default)
			)
			(layer "F.Fab")
		)
		(fp_line
			(start 0.12065 -0.2794)
			(end 0.12065 -0.3048)
			(stroke
				(width 0.1)
				(type default)
			)
			(layer "F.Fab")
		)
		(fp_line
			(start 0.67945 -0.3048)
			(end 0.67945 0.3048)
			(stroke
				(width 0.1)
				(type default)
			)
			(layer "F.Fab")
		)
		(fp_line
			(start 0.67945 0.3048)
			(end 0.120396 0.3048)
			(stroke
				(width 0.1)
				(type default)
			)
			(layer "F.Fab")
		)
		(pad "1" smd circle
			(at -0.40005 0)
			(size 0 0)
			(layers "F.Cu" "F.Mask" "F.Paste")
			(net "U39_ADJ")
		)
		(pad "2" smd circle
			(at 0.40005 0)
			(size 0 0)
			(layers "F.Cu" "F.Mask" "F.Paste")
			(net "GND")
		)
	)
	(footprint ""
		(layer "F.Cu")
		(at 15.1638 -51.1048 -90)
		(property "Reference" "U18"
			(at 0.8636 -1.83007 90)
			(unlocked yes)
			(layer "F.SilkS")
			(effects
				(font
					(size 0.7874 0.5842)
					(thickness 0.1524)
				)
			)
		)
		(property "Value" ""
			(at 0 0 270)
			(layer "F.Fab")
			(effects
				(font
					(size 1.27 1.27)
				)
			)
		)
		(duplicate_pad_numbers_are_jumpers no)
		(fp_line
			(start -1.7018 1.1176)
			(end -1.7018 -1.1176)
			(stroke
				(width 0.1524)
				(type default)
			)
			(layer "F.SilkS")
		)
		(fp_line
			(start 1.7018 1.1176)
			(end -1.7018 1.1176)
			(stroke
				(width 0.1524)
				(type default)
			)
			(layer "F.SilkS")
		)
		(fp_line
			(start 0 -0.7112)
			(end -0.254 -1.1176)
			(stroke
				(width 0.1524)
				(type default)
			)
			(layer "F.SilkS")
		)
		(fp_line
			(start -0.254 -1.1176)
			(end -1.7018 -1.1176)
			(stroke
				(width 0.1524)
				(type default)
			)
			(layer "F.SilkS")
		)
		(fp_line
			(start 0.254 -1.1176)
			(end 0 -0.7112)
			(stroke
				(width 0.1524)
				(type default)
			)
			(layer "F.SilkS")
		)
		(fp_line
			(start 1.7018 -1.1176)
			(end 1.7018 1.1176)
			(stroke
				(width 0.1524)
				(type default)
			)
			(layer "F.SilkS")
		)
		(fp_line
			(start 1.7018 -1.1176)
			(end 0.254 -1.1176)
			(stroke
				(width 0.1524)
				(type default)
			)
			(layer "F.SilkS")
		)
		(fp_poly
			(pts
				(xy -1.559814 -1.3589) (xy -1.788414 -1.9431) (xy -1.356614 -1.9431)
			)
			(stroke
				(width 0)
				(type default)
			)
			(fill yes)
			(layer "F.SilkS")
		)
		(fp_line
			(start -1.5494 1.1176)
			(end -1.5494 -1.1176)
			(stroke
				(width 0.1)
				(type default)
			)
			(layer "F.Fab")
		)
		(fp_line
			(start 1.5494 1.1176)
			(end -1.5494 1.1176)
			(stroke
				(width 0.1)
				(type default)
			)
			(layer "F.Fab")
		)
		(fp_line
			(start -0.254 -1.1176)
			(end -1.5494 -1.1176)
			(stroke
				(width 0.1)
				(type default)
			)
			(layer "F.Fab")
		)
		(fp_line
			(start 0.254 -1.1176)
			(end -0.254 -1.1176)
			(stroke
				(width 0.1)
				(type default)
			)
			(layer "F.Fab")
		)
		(fp_line
			(start 1.5494 -1.1176)
			(end 1.5494 1.1176)
			(stroke
				(width 0.1)
				(type default)
			)
			(layer "F.Fab")
		)
		(fp_line
			(start 1.5494 -1.1176)
			(end 0.254 -1.1176)
			(stroke
				(width 0.1)
				(type default)
			)
			(layer "F.Fab")
		)
		(fp_poly
			(pts
				(xy -1.8161 -0.675386) (xy -2.4003 -0.446786) (xy -2.4003 -0.878586)
			)
			(stroke
				(width 0)
				(type default)
			)
			(fill yes)
			(layer "F.Fab")
		)
		(pad "1" smd rect
			(at -0.962406 -0.649986 180)
			(size 0.3302 1.1684)
			(layers "F.Cu" "F.Mask" "F.Paste")
			(net "PWRGD_P5V_AUX")
		)
		(pad "2" smd rect
			(at -0.962406 0 180)
			(size 0.3302 1.1684)
			(layers "F.Cu" "F.Mask" "F.Paste")
			(net "PWRGD_P1V8_AUX_R2")
		)
		(pad "3" smd rect
			(at -0.962406 0.649986 180)
			(size 0.3302 1.1684)
			(layers "F.Cu" "F.Mask" "F.Paste")
			(net "GND")
		)
		(pad "4" smd rect
			(at 0.962406 0.649986 180)
			(size 0.3302 1.1684)
			(layers "F.Cu" "F.Mask" "F.Paste")
			(net "EN_P3V3_RGM")
		)
		(pad "5" smd rect
			(at 0.962406 -0.649986 180)
			(size 0.3302 1.1684)
			(layers "F.Cu" "F.Mask" "F.Paste")
			(net "P3V3_LDO")
		)
	)
	(footprint ""
		(layer "F.Cu")
		(at 24.4856 -33.909 90)
		(property "Reference" "C156"
			(at 0 0 90)
			(layer "F.SilkS")
			(hide yes)
			(effects
				(font
					(size 1.27 1.27)
				)
			)
		)
		(property "Value" ""
			(at 0 0 90)
			(layer "F.Fab")
			(effects
				(font
					(size 1.27 1.27)
				)
			)
		)
		(duplicate_pad_numbers_are_jumpers no)
		(fp_line
			(start 0.7874 -0.4064)
			(end 0.7874 0.4064)
			(stroke
				(width 0.1524)
				(type default)
			)
			(layer "F.SilkS")
		)
		(fp_line
			(start -0.7874 -0.4064)
			(end 0.7874 -0.4064)
			(stroke
				(width 0.1524)
				(type default)
			)
			(layer "F.SilkS")
		)
		(fp_line
			(start 0.7874 0.4064)
			(end -0.7874 0.4064)
			(stroke
				(width 0.1524)
				(type default)
			)
			(layer "F.SilkS")
		)
		(fp_line
			(start -0.7874 0.4064)
			(end -0.7874 -0.4064)
			(stroke
				(width 0.1524)
				(type default)
			)
			(layer "F.SilkS")
		)
		(fp_line
			(start -0.12065 -0.305054)
			(end -0.12065 -0.2794)
			(stroke
				(width 0.1)
				(type default)
			)
			(layer "F.Fab")
		)
		(fp_line
			(start -0.67945 -0.305054)
			(end -0.12065 -0.305054)
			(stroke
				(width 0.1)
				(type default)
			)
			(layer "F.Fab")
		)
		(fp_line
			(start 0.67945 -0.3048)
			(end 0.67945 0.3048)
			(stroke
				(width 0.1)
				(type default)
			)
			(layer "F.Fab")
		)
		(fp_line
			(start 0.12065 -0.3048)
			(end 0.67945 -0.3048)
			(stroke
				(width 0.1)
				(type default)
			)
			(layer "F.Fab")
		)
		(fp_line
			(start 0.12065 -0.2794)
			(end 0.12065 -0.3048)
			(stroke
				(width 0.1)
				(type default)
			)
			(layer "F.Fab")
		)
		(fp_line
			(start -0.12065 -0.2794)
			(end 0.12065 -0.2794)
			(stroke
				(width 0.1)
				(type default)
			)
			(layer "F.Fab")
		)
		(fp_line
			(start 0.120396 0.2794)
			(end -0.12065 0.2794)
			(stroke
				(width 0.1)
				(type default)
			)
			(layer "F.Fab")
		)
		(fp_line
			(start -0.12065 0.2794)
			(end -0.12065 0.3048)
			(stroke
				(width 0.1)
				(type default)
			)
			(layer "F.Fab")
		)
		(fp_line
			(start 0.67945 0.3048)
			(end 0.120396 0.3048)
			(stroke
				(width 0.1)
				(type default)
			)
			(layer "F.Fab")
		)
		(fp_line
			(start 0.120396 0.3048)
			(end 0.120396 0.2794)
			(stroke
				(width 0.1)
				(type default)
			)
			(layer "F.Fab")
		)
		(fp_line
			(start -0.12065 0.3048)
			(end -0.67945 0.3048)
			(stroke
				(width 0.1)
				(type default)
			)
			(layer "F.Fab")
		)
		(fp_line
			(start -0.67945 0.3048)
			(end -0.67945 -0.305054)
			(stroke
				(width 0.1)
				(type default)
			)
			(layer "F.Fab")
		)
		(pad "1" smd circle
			(at -0.40005 0 90)
			(size 0 0)
			(layers "F.Cu" "F.Mask" "F.Paste")
			(net "PWRGD_P1V0_AUX_R")
		)
		(pad "2" smd circle
			(at 0.40005 0 90)
			(size 0 0)
			(layers "F.Cu" "F.Mask" "F.Paste")
			(net "GND")
		)
	)
	(footprint ""
		(layer "F.Cu")
		(at 50.3174 -68.2498)
		(property "Reference" "R774"
			(at 0 0 0)
			(layer "F.SilkS")
			(hide yes)
			(effects
				(font
					(size 1.27 1.27)
				)
			)
		)
		(property "Value" ""
			(at 0 0 0)
			(layer "F.Fab")
			(effects
				(font
					(size 1.27 1.27)
				)
			)
		)
		(duplicate_pad_numbers_are_jumpers no)
		(fp_line
			(start -0.7874 -0.4064)
			(end 0.7874 -0.4064)
			(stroke
				(width 0.1524)
				(type default)
			)
			(layer "F.SilkS")
		)
		(fp_line
			(start -0.7874 0.4064)
			(end -0.7874 -0.4064)
			(stroke
				(width 0.1524)
				(type default)
			)
			(layer "F.SilkS")
		)
		(fp_line
			(start 0.7874 -0.4064)
			(end 0.7874 0.4064)
			(stroke
				(width 0.1524)
				(type default)
			)
			(layer "F.SilkS")
		)
		(fp_line
			(start 0.7874 0.4064)
			(end -0.7874 0.4064)
			(stroke
				(width 0.1524)
				(type default)
			)
			(layer "F.SilkS")
		)
		(fp_line
			(start -0.67945 -0.305054)
			(end -0.12065 -0.305054)
			(stroke
				(width 0.1)
				(type default)
			)
			(layer "F.Fab")
		)
		(fp_line
			(start -0.67945 0.3048)
			(end -0.67945 -0.305054)
			(stroke
				(width 0.1)
				(type default)
			)
			(layer "F.Fab")
		)
		(fp_line
			(start -0.12065 -0.305054)
			(end -0.12065 -0.2794)
			(stroke
				(width 0.1)
				(type default)
			)
			(layer "F.Fab")
		)
		(fp_line
			(start -0.12065 -0.2794)
			(end 0.12065 -0.2794)
			(stroke
				(width 0.1)
				(type default)
			)
			(layer "F.Fab")
		)
		(fp_line
			(start -0.12065 0.2794)
			(end -0.12065 0.3048)
			(stroke
				(width 0.1)
				(type default)
			)
			(layer "F.Fab")
		)
		(fp_line
			(start -0.12065 0.3048)
			(end -0.67945 0.3048)
			(stroke
				(width 0.1)
				(type default)
			)
			(layer "F.Fab")
		)
		(fp_line
			(start 0.120396 0.2794)
			(end -0.12065 0.2794)
			(stroke
				(width 0.1)
				(type default)
			)
			(layer "F.Fab")
		)
		(fp_line
			(start 0.120396 0.3048)
			(end 0.120396 0.2794)
			(stroke
				(width 0.1)
				(type default)
			)
			(layer "F.Fab")
		)
		(fp_line
			(start 0.12065 -0.3048)
			(end 0.67945 -0.3048)
			(stroke
				(width 0.1)
				(type default)
			)
			(layer "F.Fab")
		)
		(fp_line
			(start 0.12065 -0.2794)
			(end 0.12065 -0.3048)
			(stroke
				(width 0.1)
				(type default)
			)
			(layer "F.Fab")
		)
		(fp_line
			(start 0.67945 -0.3048)
			(end 0.67945 0.3048)
			(stroke
				(width 0.1)
				(type default)
			)
			(layer "F.Fab")
		)
		(fp_line
			(start 0.67945 0.3048)
			(end 0.120396 0.3048)
			(stroke
				(width 0.1)
				(type default)
			)
			(layer "F.Fab")
		)
		(pad "1" smd circle
			(at -0.40005 0)
			(size 0 0)
			(layers "F.Cu" "F.Mask" "F.Paste")
			(net "P3V3_AUX")
		)
		(pad "2" smd circle
			(at 0.40005 0)
			(size 0 0)
			(layers "F.Cu" "F.Mask" "F.Paste")
			(net "FM_SLPS3_GF_N")
		)
	)
	(footprint ""
		(layer "F.Cu")
		(at 50.8 -30.861 90)
		(property "Reference" "R150"
			(at 0 0 90)
			(layer "F.SilkS")
			(hide yes)
			(effects
				(font
					(size 1.27 1.27)
				)
			)
		)
		(property "Value" ""
			(at 0 0 90)
			(layer "F.Fab")
			(effects
				(font
					(size 1.27 1.27)
				)
			)
		)
		(duplicate_pad_numbers_are_jumpers no)
		(fp_line
			(start 0.7874 -0.4064)
			(end 0.7874 0.4064)
			(stroke
				(width 0.1524)
				(type default)
			)
			(layer "F.SilkS")
		)
		(fp_line
			(start -0.7874 -0.4064)
			(end 0.7874 -0.4064)
			(stroke
				(width 0.1524)
				(type default)
			)
			(layer "F.SilkS")
		)
		(fp_line
			(start 0.7874 0.4064)
			(end -0.7874 0.4064)
			(stroke
				(width 0.1524)
				(type default)
			)
			(layer "F.SilkS")
		)
		(fp_line
			(start -0.7874 0.4064)
			(end -0.7874 -0.4064)
			(stroke
				(width 0.1524)
				(type default)
			)
			(layer "F.SilkS")
		)
		(fp_line
			(start -0.12065 -0.305054)
			(end -0.12065 -0.2794)
			(stroke
				(width 0.1)
				(type default)
			)
			(layer "F.Fab")
		)
		(fp_line
			(start -0.67945 -0.305054)
			(end -0.12065 -0.305054)
			(stroke
				(width 0.1)
				(type default)
			)
			(layer "F.Fab")
		)
		(fp_line
			(start 0.67945 -0.3048)
			(end 0.67945 0.3048)
			(stroke
				(width 0.1)
				(type default)
			)
			(layer "F.Fab")
		)
		(fp_line
			(start 0.12065 -0.3048)
			(end 0.67945 -0.3048)
			(stroke
				(width 0.1)
				(type default)
			)
			(layer "F.Fab")
		)
		(fp_line
			(start 0.12065 -0.2794)
			(end 0.12065 -0.3048)
			(stroke
				(width 0.1)
				(type default)
			)
			(layer "F.Fab")
		)
		(fp_line
			(start -0.12065 -0.2794)
			(end 0.12065 -0.2794)
			(stroke
				(width 0.1)
				(type default)
			)
			(layer "F.Fab")
		)
		(fp_line
			(start 0.120396 0.2794)
			(end -0.12065 0.2794)
			(stroke
				(width 0.1)
				(type default)
			)
			(layer "F.Fab")
		)
		(fp_line
			(start -0.12065 0.2794)
			(end -0.12065 0.3048)
			(stroke
				(width 0.1)
				(type default)
			)
			(layer "F.Fab")
		)
		(fp_line
			(start 0.67945 0.3048)
			(end 0.120396 0.3048)
			(stroke
				(width 0.1)
				(type default)
			)
			(layer "F.Fab")
		)
		(fp_line
			(start 0.120396 0.3048)
			(end 0.120396 0.2794)
			(stroke
				(width 0.1)
				(type default)
			)
			(layer "F.Fab")
		)
		(fp_line
			(start -0.12065 0.3048)
			(end -0.67945 0.3048)
			(stroke
				(width 0.1)
				(type default)
			)
			(layer "F.Fab")
		)
		(fp_line
			(start -0.67945 0.3048)
			(end -0.67945 -0.305054)
			(stroke
				(width 0.1)
				(type default)
			)
			(layer "F.Fab")
		)
		(pad "1" smd circle
			(at -0.40005 0 90)
			(size 0 0)
			(layers "F.Cu" "F.Mask" "F.Paste")
			(net "SGPIO_LD_1")
		)
		(pad "2" smd circle
			(at 0.40005 0 90)
			(size 0 0)
			(layers "F.Cu" "F.Mask" "F.Paste")
			(net "SGPIO_BMC_M1_LD")
		)
	)
)
